FILE_TYPE = CONNECTIVITY;
{Allegro Design Entry HDL 16.6-p007 (v16-6-112F) 10/10/2012}
"PAGE_NUMBER" = 114;
0"NC";
1"GND\g";
2"GND\g";
3"GND\g";
4"GND\g";
5"CLK_100M_SRC13_DP";
6"CLK_100M_SRC13_DN";
7"CLK_100M_MEZZ4_DP";
8"CLK_100M_MEZZ4_DN";
9"CLK_100M_MEZZ3_DP";
10"TP_CLK_24M_PMSYNC2";
11"CLK_100M_AIRMAX8_PE1_DN";
12"CLK_100M_DB1200_DN";
13"CLK_100M_PCH_SLOTX24_S1_DP";
14"CLK_100M_PCH_SLOTX24_S3_DN";
15"CLK_100M_PCH_SLOTX24_S3_DP";
16"CLK_100M_PCH_SLOTX24_S4_DN";
17"CLK_100M_PCH_SLOTX24_S2_DP";
18"CLK_48M_USB_BMC";
19"CLK_100M_SRC12_DN";
20"CLK_100M_SRC12_DP";
21"CLK_100M_SPRV_DN";
22"CLK_100M_SPRV_DP";
23"CLK_100M_M2_DN";
24"CLK_100M_M2_DP";
25"H_PMSYNC_CLK_24M";
26"CLK_100M_PCH_SLOTX24_S5_DN";
27"CLK_100M_PCH_SLOTX24_S4_DP";
28"CLK_100M_PCH_SLOTX24_S2_DN";
29"CLK_100M_PCH_SLOTX24_S1_DN";
30"XTAL_33K_RTC1";
31"XTAL_PCH_48M_OUT";
32"XTAL_PCH_48M_IN";
33"XTAL_PCH_48M_IN";
34"H_PMSYNC_CLK_24M_R";
35"CLK_100M_PCH_SLOTX24_S0_DP";
36"CLK_100M_PCH_SLOTX24_S0_DN";
37"CLK_100M_DB1200_DP";
38"CLK_100M_AIRMAX8_PE1_DP";
39"CLK_100M_MEZZ1_DN";
40"CLK_100M_MEZZ1_DP";
41"CLK_100M_MEZZ2_DP";
42"CLK_100M_MEZZ2_DN";
43"CLK_100M_MEZZ3_DN";
44"CLK_100M_PCH_SLOTX24_S5_DP";
45"XTAL_33K_RTC2";
46"TP_PCH_RSVD64";
47"TP_PCH_RSVD65";
48"CLK_100M_BMC_PE_DP";
49"CLK_100M_BMC_PE_DN";
50"A_PCH_XCLK_BIASREF";
51"TP_CLK_100M_PLAT1_DP";
52"TP_CLK_100M_PLAT1_DN";
53"TP_CLK_100M_NSSCC1_DP";
54"TP_CLK_100M_NSSCC1_DN";
55"TP_CLK_100M_NSSCC0_DP";
56"TP_CLK_100M_NSSCC0_DN";
57"XTAL_33K_RTC2";
58"XTAL_PCH_48M_OUT";
59"CLK_100M_BMC_PE_R_DN";
60"CLK_100M_BMC_PE_R_DP";
61"CLK_100M_PCH_XDP_DN";
62"CLK_100M_PCH_XDP_DP";
63"XTAL_33K_RTC1";
%"RES"
"1","(2300,1350)","0","mstr_discrete","I110";
;
CDS_SEC"1"
SEC"1"
SEC_TYPE"0402"
ROOM"SB"
CDS_LOCATION"R8B20"
CDS_LIB"mstr_discrete"
PACK_TYPE"0402"
MATERIAL"CHIP"
LOCATION"R8B20"
PART_NUMBER"G21796-066"
TOLERANCE"1%"
VALUE"10.0"
WATTAGE"1/16W";
"B"
$PN"2"25;
"A"
$PN"1"34;
%"RES"
"2","(2900,1100)","0","mstr_discrete","I124";
;
CDS_SEC"1"
SEC_TYPE"0402"
SEC"1"
ROOM"SB"
CDS_LOCATION"R8B21"
CDS_LIB"mstr_discrete"
LOCATION"R8B21"
WATTAGE"1/16W"
TOLERANCE"1%"
VALUE"49.9"
MATERIAL"EMPTY"
PACK_TYPE"0402"
PART_NUMBER"G21796-047";
"A"
$PN"1"25;
"B"
$PN"2"1;
%"GND"
"1","(2900,850)","0","mstr_symbols","I125";
;
HDL_POWER"GND"
SIZE"1B"
VOLTAGE"0.0V"
CDS_LIB"mstr_symbols"
BODY_TYPE"PLUMBING";
"A\NAC"1;
%"RES"
"1","(-1175,2800)","0","mstr_discrete","I141";
;
CDS_SEC"1"
BOM_COST"SB"
SEC"1"
SEC_TYPE"0402"
ROOM"SB"
CDS_LOCATION"R7C2"
CDS_LIB"mstr_discrete"
PACK_TYPE"0402"
MATERIAL"EMPTY"
PART_NUMBER"G21497-005"
LOCATION"R7C2"
TOLERANCE"5%"
VALUE"0.0"
WATTAGE"1/16W";
"B"
$PN"2"49;
"A"
$PN"1"59;
%"RES"
"1","(-1625,2850)","0","mstr_discrete","I142";
;
CDS_SEC"1"
BOM_COST"SB"
SEC_TYPE"0402"
SEC"1"
ROOM"SB"
CDS_LIB"mstr_discrete"
CDS_LOCATION"R7C4"
PACK_TYPE"0402"
MATERIAL"EMPTY"
LOCATION"R7C4"
PART_NUMBER"G21497-005"
TOLERANCE"5%"
VALUE"0.0"
WATTAGE"1/16W";
"B"
$PN"2"48;
"A"
$PN"1"60;
%"RES"
"2","(-2950,2750)","0","mstr_discrete","I149";
;
$SEC"1"
CDS_SEC"1"
CDS_LOCATION"R3N1"
ROOM"SB"
CDS_LIB"mstr_discrete"
LOCATION"R3N1"
PART_NUMBER"G21796-276"
TOLERANCE"1.0%"
PACK_TYPE"0402"
MATERIAL"CHIP"
WATTAGE"1/16W"
VALUE"169";
"A"
$PN"1"50;
"B"
$PN"2"2;
%"GND"
"1","(-2950,2500)","0","mstr_symbols","I150";
;
HDL_POWER"GND"
BODY_TYPE"PLUMBING"
SIZE"1B"
CDS_LIB"mstr_symbols"
VOLTAGE"0.0V";
"A\NAC"2;
%"LBG_CORE_QAT_EXT_D"
"1","(525,2150)","0","mstr_u_proc","I40";
;
CDS_SEC"1"
CDS_LIB"mstr_u_proc"
PACK_TYPE"BGA1"
CDS_LOCATION"U7C1"
BOM_COST"SB"
SEC"1"
SEC_TYPE"BGA1"
ROOM"SB"
LOCATION"U7C1"
MATERIAL"IC"
PART_NUMBER"H91415-002";
"CLKOUT_ITPXDPN"
$PN"A39"61;
"CLKOUT_ITPXDPP"
$PN"C39"62;
"CLKOUT_NSSCCAP0N"
$PN"A32"56;
"CLKOUT_NSSCCAP0P"
$PN"C32"55;
"CLKOUT_NSSCCAP1N"
$PN"B38"54;
"CLKOUT_NSSCCAP1P"
$PN"D38"53;
"CLKOUT_PLAT0N"
$PN"B29"49;
"CLKOUT_PLAT0P"
$PN"D29"48;
"CLKOUT_PLAT1N"
$PN"B40"52;
"CLKOUT_PLAT1P"
$PN"D40"51;
"CLKOUT_SRCN<15>"
$PN"K27"23;
"CLKOUT_SRCN<14>"
$PN"C20"21;
"CLKOUT_SRCN<13>"
$PN"C24"6;
"CLKOUT_SRCN<12>"
$PN"K24"19;
"CLKOUT_SRCN<11>"
$PN"B21"8;
"CLKOUT_SRCN<10>"
$PN"B23"43;
"CLKOUT_SRCN<9>"
$PN"J26"42;
"CLKOUT_SRCN<8>"
$PN"D31"39;
"CLKOUT_SRCN<7>"
$PN"H31"26;
"CLKOUT_SRCN<6>"
$PN"D33"16;
"CLKOUT_SRCN<5>"
$PN"J40"14;
"CLKOUT_SRCN<4>"
$PN"A28"28;
"CLKOUT_SRCN<3>"
$PN"K42"29;
"CLKOUT_SRCN<2>"
$PN"J33"36;
"CLKOUT_SRCN<1>"
$PN"K35"12;
"CLKOUT_SRCN<0>"
$PN"K38"11;
"CLKOUT_SRCP<15>"
$PN"H27"24;
"CLKOUT_SRCP<14>"
$PN"A20"22;
"CLKOUT_SRCP<13>"
$PN"A24"5;
"CLKOUT_SRCP<12>"
$PN"H24"20;
"CLKOUT_SRCP<11>"
$PN"D21"7;
"CLKOUT_SRCP<10>"
$PN"D23"9;
"CLKOUT_SRCP<9>"
$PN"G26"41;
"CLKOUT_SRCP<8>"
$PN"B31"40;
"CLKOUT_SRCP<7>"
$PN"K31"44;
"CLKOUT_SRCP<6>"
$PN"B33"27;
"CLKOUT_SRCP<5>"
$PN"G40"15;
"CLKOUT_SRCP<4>"
$PN"C28"17;
"CLKOUT_SRCP<3>"
$PN"H42"13;
"CLKOUT_SRCP<2>"
$PN"G33"35;
"CLKOUT_SRCP<1>"
$PN"H35"37;
"CLKOUT_SRCP<0>"
$PN"H38"38;
"CLOCKSE_BMCCLK"
$PN"BW50"18;
"CLOCKSE_PMSYNCCLK1"
$PN"BY51"34;
"CLOCKSE_PMSYNCCLK2"
$PN"BV51"10;
"RSVD<65>"
$PN"A26"47;
"RSVD<64>"
$PN"C26"46;
"RTCX1"
$PN"K17"63;
"RTCX2"
$PN"H17"57;
"XCLK_BIASREF"
$PN"G44"50;
"XTAL_IN"
$PN"B35"33;
"XTAL_OUT"
$PN"D35"58;
%"CAP"
"1","(225,-225)","0","mstr_discrete","I46";
;
CDS_SEC"1"
$SEC"1"
CDS_LOCATION"C7C15"
ROOM"SB"
CDS_LIB"mstr_discrete"
PART_NUMBER"A36095-042"
TOLERANCE"5%"
VALUE"18PF"
VOLTAGE"50V"
PACK_TYPE"0402LF"
LOCATION"C7C15"
MATERIAL"C0G";
"A"
$PN"1"45;
"B"
$PN"2"4;
%"CAP"
"1","(-1525,-225)","0","mstr_discrete","I47";
;
CDS_SEC"1"
SEC_TYPE"0402LF"
SEC"1"
ROOM"SB"
CDS_LIB"mstr_discrete"
BOM_COST"SYS_CLOCK"
CDS_LOCATION"C7C5"
PART_NUMBER"A36095-047"
LOCATION"C7C5"
VALUE"15.0PF"
VOLTAGE"50V"
TOLERANCE"5%"
MATERIAL"COG"
PACK_TYPE"0402LF";
"A"
$PN"1"31;
"B"
$PN"2"3;
%"RES"
"1","(-1775,475)","0","mstr_discrete","I48";
;
CDS_SEC"1"
SEC_TYPE"0603"
SEC"1"
CDS_LOCATION"R7C1"
CDS_LIB"mstr_discrete"
ROOM"SB"
PART_NUMBER"G22369-010"
PACK_TYPE"0603"
TOLERANCE"0.1%"
MATERIAL"CHIP"
WATTAGE"1/10W"
VALUE"200K"
LOCATION"R7C1";
"B"
$PN"2"31;
"A"
$PN"1"32;
%"CRYSTAL"
"1","(-1775,125)","0","mstr_discrete","I49";
;
CDS_SEC"1"
ROOM"SB"
SEC"1"
SEC_TYPE"2013"
CDS_LOCATION"Y7C1"
PACK_TYPE"2013"
CDS_LIB"mstr_discrete"
MATERIAL"IC"
LOCATION"Y7C1"
VALUE"48.000MHZ"
PART_NUMBER"D71700-058";
"B"
$PN"3"31;
"A"
$PN"1"32;
%"CAP"
"1","(-2025,-225)","0","mstr_discrete","I50";
;
CDS_SEC"1"
SEC_TYPE"0402LF"
SEC"1"
CDS_LIB"mstr_discrete"
CDS_LOCATION"C7C4"
ROOM"SB"
BOM_COST"SYS_CLOCK"
PART_NUMBER"A36095-047"
LOCATION"C7C4"
VALUE"15.0PF"
VOLTAGE"50V"
TOLERANCE"5%"
PACK_TYPE"0402LF"
MATERIAL"COG";
"A"
$PN"1"32;
"B"
$PN"2"3;
%"GND"
"1","(-2025,-575)","0","mstr_symbols","I53";
;
HDL_POWER"GND"
CDS_LIB"mstr_symbols"
SIZE"1B"
VOLTAGE"0"
BOM_COST"SYS_CLOCK"
BODY_TYPE"PLUMBING";
"A\NAC"3;
%"RES"
"1","(-25,475)","0","mstr_discrete","I54";
;
CDS_SEC"1"
$SEC"1"
CDS_LOCATION"R7C6"
CDS_LIB"mstr_discrete"
ROOM"SB"
BOM_COST"SYS_CLOCK"
LOCATION"R7C6"
PART_NUMBER"G22026-112"
TOLERANCE"1.0%"
WATTAGE"1/10W"
VALUE"10M"
MATERIAL"CHIP"
PACK_TYPE"0603";
"B"
$PN"2"45;
"A"
$PN"1"30;
%"CRYSTAL"
"1","(-25,125)","0","mstr_discrete","I55";
;
CDS_SEC"1"
SEC_TYPE"SM"
SEC"1"
ROOM"SB"
CDS_LOCATION"Y7C2"
CDS_LIB"mstr_discrete"
PACK_TYPE"SM"
LOCATION"Y7C2"
PART_NUMBER"C13544-023"
VALUE"32.768KHZ"
MATERIAL"IC";
"B"
$PN"2"45;
"A"
$PN"1"30;
%"CAP"
"1","(-275,-225)","0","mstr_discrete","I56";
;
CDS_SEC"1"
$SEC"1"
ROOM"SB"
CDS_LOCATION"C7C13"
CDS_LIB"mstr_discrete"
PART_NUMBER"A36095-042"
PACK_TYPE"0402LF"
TOLERANCE"5%"
VALUE"18PF"
LOCATION"C7C13"
VOLTAGE"50V"
MATERIAL"C0G";
"A"
$PN"1"30;
"B"
$PN"2"4;
%"GND"
"1","(-275,-575)","0","mstr_symbols","I57";
;
HDL_POWER"GND"
VOLTAGE"0"
SIZE"1B"
CDS_LIB"mstr_symbols"
BODY_TYPE"PLUMBING"
BOM_COST"SYS_CLOCK";
"A\NAC"4;
END.
